# T6G (Grand Teton) — schematic netlist excerpt (pin names and nets, part order shuffled) for the footprints in the layout excerpt that follows; sources: Cadence DE-HDL packaged netlist, KiCad conversion of 04192023_DAF0TMB3IC0_F0TG_MB_C_brd_V02_OCP.brd

PU53  ISL99390FRZTR5935  ISL99390FRZ-TR5935 IC  pkg QFN21_6X5XB  page 223
  VOS  = PVDDIO_P1_VOS4
  AGND  = GND
  VCC  = PVDDIO_P1_VCC4
  PVCC  = PVDDCR_CPU1_P1_PVCC
  PGND1  = GND
  GL1  = NC_PVDDIO_P1_GL1_4
  PGND2  = GND
  SW  = SW_PVDDIO_P1_SW4
  VIN1  = SW_P12V_AUX_PVDDIO_P1_FLT
  VIN2  = SW_P12V_AUX_PVDDIO_P1_FLT
  DNC  = NC_PVDDIO_P1_DNC4
  PHASE  = SW_PVDDIO_P1_BOOTR4
  BOOT  = SW_PVDDIO_P1_BOOT4
  PWM  = PVDDIO_P1_PWM4
  EN  = PVDDIO_P1_VCC4
  TOUT_FLT  = PVDDIO_P1_TEMP1
  LSET  = PVDDIO_P1_LSET4
  IOUT  = PVDDIO_P1_IMON4
  REFIN  = PVDDCR_CPU1_P1_VCCS
  PGND3  = GND
  GL2  = NC_PVDDIO_P1_GL2_4

(kicad_pcb
	(version 20260206)
	(generator "pcbnew")
	(generator_version "10.0")
	(general
		(thickness 1.6)
		(legacy_teardrops no)
	)
	(paper "A4")
	(title_block
		(title "04192023_DAF0TMB3IC0_F0TG_MB_C_brd_V02_OCP.brd")
		(comment 1 "Grand Teton / footprints 1357-1357 of 8354")
	)
	(layers
		(0 "F.Cu" signal "TOP")
		(4 "In1.Cu" signal "GND")
		(6 "In2.Cu" signal "IN1")
		(8 "In3.Cu" signal "GND1")
		(10 "In4.Cu" signal "IN2")
		(12 "In5.Cu" signal "GND2")
		(14 "In6.Cu" signal "IN3")
		(16 "In7.Cu" signal "GND3")
		(18 "In8.Cu" signal "VCC")
		(20 "In9.Cu" signal "VCC1")
		(22 "In10.Cu" signal "GND4")
		(24 "In11.Cu" signal "IN4")
		(26 "In12.Cu" signal "GND5")
		(28 "In13.Cu" signal "IN5")
		(30 "In14.Cu" signal "GND6")
		(32 "In15.Cu" signal "IN6")
		(34 "In16.Cu" signal "GND7")
		(2 "B.Cu" signal "BOTTOM")
		(9 "F.Adhes" user "F.Adhesive")
		(11 "B.Adhes" user "B.Adhesive")
		(13 "F.Paste" user "Package Geometry/Pastemask Top")
		(15 "B.Paste" user "Package Geometry/Pastemask Bottom")
		(5 "F.SilkS" user "Ref Des/Silkscreen Top")
		(7 "B.SilkS" user "Ref Des/Silkscreen Bottom")
		(1 "F.Mask" user "Board Geometry/Soldermask Top")
		(3 "B.Mask" user "Board Geometry/Soldermask Bottom")
		(17 "Dwgs.User" user "User.Drawings")
		(19 "Cmts.User" user "User.Comments")
		(21 "Eco1.User" user "User.Eco1")
		(23 "Eco2.User" user "User.Eco2")
		(25 "Edge.Cuts" user "Board Geometry/Outline")
		(27 "Margin" user)
		(31 "F.CrtYd" user "Package Geometry/Place Bound Top")
		(29 "B.CrtYd" user "Package Geometry/Place Bound Bottom")
		(35 "F.Fab" user "Ref Des/Assembly Top")
		(33 "B.Fab" user "Ref Des/Assembly Bottom")
	)
	(footprint ""
		(layer "F.Cu")
		(at 28.600654 -346.721176)
		(property "Reference" "PU53"
			(at -3.073654 -7.709154 0)
			(unlocked yes)
			(layer "F.SilkS")
			(effects
				(font
					(size 0.7874 0.5842)
					(thickness 0.1524)
				)
				(justify left)
			)
		)
		(property "Value" ""
			(at 0 0 0)
			(layer "F.Fab")
			(effects
				(font
					(size 1.27 1.27)
				)
			)
		)
		(duplicate_pad_numbers_are_jumpers no)
		(fp_line
			(start -2.500122 -2.999994)
			(end -2.24409 -2.999994)
			(stroke
				(width 0.1524)
				(type default)
			)
			(layer "F.SilkS")
		)
		(fp_line
			(start -2.500122 -2.529078)
			(end -2.500122 -2.999994)
			(stroke
				(width 0.1524)
				(type default)
			)
			(layer "F.SilkS")
		)
		(fp_line
			(start -2.500122 0.6604)
			(end -2.500122 0.229108)
			(stroke
				(width 0.1524)
				(type default)
			)
			(layer "F.SilkS")
		)
		(fp_line
			(start -2.500122 2.999994)
			(end -2.500122 2.339594)
			(stroke
				(width 0.1524)
				(type default)
			)
			(layer "F.SilkS")
		)
		(fp_line
			(start -2.2987 2.999994)
			(end -2.500122 2.999994)
			(stroke
				(width 0.1524)
				(type default)
			)
			(layer "F.SilkS")
		)
		(fp_line
			(start 2.31394 -2.999994)
			(end 2.500122 -2.999994)
			(stroke
				(width 0.1524)
				(type default)
			)
			(layer "F.SilkS")
		)
		(fp_line
			(start 2.500122 -2.999994)
			(end 2.500122 -2.44348)
			(stroke
				(width 0.1524)
				(type default)
			)
			(layer "F.SilkS")
		)
		(fp_line
			(start 2.500122 2.339594)
			(end 2.500122 2.999994)
			(stroke
				(width 0.1524)
				(type default)
			)
			(layer "F.SilkS")
		)
		(fp_line
			(start 2.500122 2.999994)
			(end 2.2987 2.999994)
			(stroke
				(width 0.1524)
				(type default)
			)
			(layer "F.SilkS")
		)
		(fp_poly
			(pts
				(xy -2.758948 -2.432558) (xy -3.432556 -2.657094) (xy -2.983484 -3.105912)
			)
			(stroke
				(width 0)
				(type default)
			)
			(fill yes)
			(layer "F.SilkS")
		)
		(fp_line
			(start -2.500122 -2.999994)
			(end 2.500122 -2.999994)
			(stroke
				(width 0.1)
				(type default)
			)
			(layer "F.Fab")
		)
		(fp_line
			(start -2.500122 2.999994)
			(end -2.500122 -2.999994)
			(stroke
				(width 0.1)
				(type default)
			)
			(layer "F.Fab")
		)
		(fp_line
			(start 2.500122 -2.999994)
			(end 2.500122 2.999994)
			(stroke
				(width 0.1)
				(type default)
			)
			(layer "F.Fab")
		)
		(fp_line
			(start 2.500122 2.999994)
			(end -2.500122 2.999994)
			(stroke
				(width 0.1)
				(type default)
			)
			(layer "F.Fab")
		)
		(fp_poly
			(pts
				(xy -4.218432 -2.783078) (xy -4.218432 -1.767078) (xy -3.202432 -2.275078)
			)
			(stroke
				(width 0)
				(type default)
			)
			(fill yes)
			(layer "F.Fab")
		)
		(pad "1" smd rect
			(at -2.400046 -2.275078 90)
			(size 0.2286 0.6096)
			(layers "F.Cu" "F.Mask" "F.Paste")
			(net "PVDDIO_P1_VOS4")
		)
		(pad "2" smd rect
			(at -2.400046 -1.82499 90)
			(size 0.2286 0.6096)
			(layers "F.Cu" "F.Mask" "F.Paste")
			(net "GND")
		)
		(pad "3" smd rect
			(at -2.400046 -1.374902 90)
			(size 0.2286 0.6096)
			(layers "F.Cu" "F.Mask" "F.Paste")
			(net "PVDDIO_P1_VCC4")
		)
		(pad "4" smd rect
			(at -2.400046 -0.925068 90)
			(size 0.2286 0.6096)
			(layers "F.Cu" "F.Mask" "F.Paste")
			(net "PVDDCR_CPU1_P1_PVCC")
		)
		(pad "5" smd rect
			(at -2.400046 -0.47498 90)
			(size 0.2286 0.6096)
			(layers "F.Cu" "F.Mask" "F.Paste")
			(net "GND")
		)
		(pad "6" smd rect
			(at -2.400046 -0.024892 90)
			(size 0.2286 0.6096)
			(layers "F.Cu" "F.Mask" "F.Paste")
			(net "NC_PVDDIO_P1_GL1_4")
		)
		(pad "7_9-20_24" smd circle
			(at 0 1.150112 90)
			(size 0 0)
			(layers "F.Cu" "F.Mask" "F.Paste")
			(net "GND")
		)
		(pad "10_19" smd rect
			(at 0 2.899918 90)
			(size 0.6096 4.318)
			(layers "F.Cu" "F.Mask" "F.Paste")
			(net "SW_PVDDIO_P1_SW4")
		)
		(pad "25_29" smd rect
			(at 1.549908 -1.279906 270)
			(size 2.0574 2.3114)
			(layers "F.Cu" "F.Mask" "F.Paste")
			(net "SW_P12V_AUX_PVDDIO_P1_FLT")
		)
		(pad "30" smd rect
			(at 2.05994 -2.899918)
			(size 0.2286 0.6096)
			(layers "F.Cu" "F.Mask" "F.Paste")
			(net "SW_P12V_AUX_PVDDIO_P1_FLT")
		)
		(pad "31" smd rect
			(at 1.610106 -2.899918)
			(size 0.2286 0.6096)
			(layers "F.Cu" "F.Mask" "F.Paste")
			(net "NC_PVDDIO_P1_DNC4")
		)
		(pad "32" smd rect
			(at 1.160018 -2.899918)
			(size 0.2286 0.6096)
			(layers "F.Cu" "F.Mask" "F.Paste")
			(net "SW_PVDDIO_P1_BOOTR4")
		)
		(pad "33" smd rect
			(at 0.70993 -2.899918)
			(size 0.2286 0.6096)
			(layers "F.Cu" "F.Mask" "F.Paste")
			(net "SW_PVDDIO_P1_BOOT4")
		)
		(pad "34" smd rect
			(at 0.260096 -2.899918)
			(size 0.2286 0.6096)
			(layers "F.Cu" "F.Mask" "F.Paste")
			(net "PVDDIO_P1_PWM4")
		)
		(pad "35" smd rect
			(at -0.189992 -2.899918)
			(size 0.2286 0.6096)
			(layers "F.Cu" "F.Mask" "F.Paste")
			(net "PVDDIO_P1_VCC4")
		)
		(pad "36" smd rect
			(at -0.64008 -2.899918)
			(size 0.2286 0.6096)
			(layers "F.Cu" "F.Mask" "F.Paste")
			(net "PVDDIO_P1_TEMP1")
		)
		(pad "37" smd rect
			(at -1.089914 -2.899918)
			(size 0.2286 0.6096)
			(layers "F.Cu" "F.Mask" "F.Paste")
			(net "PVDDIO_P1_LSET4")
		)
		(pad "38" smd rect
			(at -1.540002 -2.899918)
			(size 0.2286 0.6096)
			(layers "F.Cu" "F.Mask" "F.Paste")
			(net "PVDDIO_P1_IMON4")
		)
		(pad "39" smd rect
			(at -1.99009 -2.899918)
			(size 0.2286 0.6096)
			(layers "F.Cu" "F.Mask" "F.Paste")
			(net "PVDDCR_CPU1_P1_VCCS")
		)
		(pad "40" smd rect
			(at -0.87503 -1.27508)
			(size 1.7526 1.9558)
			(layers "F.Cu" "F.Mask" "F.Paste")
			(net "GND")
		)
		(pad "41" smd rect
			(at -1.525016 0.249936 270)
			(size 0.3048 0.4572)
			(layers "F.Cu" "F.Mask" "F.Paste")
			(net "NC_PVDDIO_P1_GL2_4")
		)
		(zone
			(layer "F.Cu")
			(hatch none 0.5)
			(connect_pads
				(clearance 0)
			)
			(min_thickness 0.25)
			(keepout
				(tracks not_allowed)
				(vias allowed)
				(pads allowed)
				(copperpour not_allowed)
				(footprints allowed)
			)
			(placement
				(enabled no)
				(sheetname "")
			)
			(fill
				(thermal_gap 0.5)
				(thermal_bridge_width 0.5)
				(island_removal_mode 0)
			)
			(polygon
				(pts
					(xy 26.100532 -344.470482) (xy 31.100776 -344.470482) (xy 31.100776 -344.176858) (xy 26.100532 -344.176858)
				)
			)
		)
		(zone
			(layer "F.Cu")
			(hatch none 0.5)
			(connect_pads
				(clearance 0)
			)
			(min_thickness 0.25)
			(keepout
				(tracks not_allowed)
				(vias allowed)
				(pads allowed)
				(copperpour not_allowed)
				(footprints allowed)
			)
			(placement
				(enabled no)
				(sheetname "")
			)
			(fill
				(thermal_gap 0.5)
				(thermal_bridge_width 0.5)
				(island_removal_mode 0)
			)
			(polygon
				(pts
					(xy 26.556208 -348.381066) (xy 26.655014 -348.381066) (xy 26.798524 -348.237556) (xy 26.798524 -347.504512)
					(xy 26.655268 -347.361256) (xy 26.556208 -347.361256)
				)
			)
		)
	)
)
